(kicad_pcb
	(version 20260206)
	(generator "pcbnew")
	(generator_version "10.0")
	(general
		(thickness 1.6)
		(legacy_teardrops no)
	)
	(paper "A4")
	(title_block
		(title "01162023_DA0F0TEBIF0_F0T_Expander_BD_F_brd_V02_OCP.brd")
		(comment 1 "Grand Teton / footprints 1762-1767 of 9728")
	)
	(layers
		(0 "F.Cu" signal "TOP")
		(4 "In1.Cu" signal "GND")
		(6 "In2.Cu" signal "VCC")
		(8 "In3.Cu" signal "VCC1")
		(10 "In4.Cu" signal "GND1")
		(12 "In5.Cu" signal "IN1")
		(14 "In6.Cu" signal "GND2")
		(16 "In7.Cu" signal "IN2")
		(18 "In8.Cu" signal "GND3")
		(20 "In9.Cu" signal "IN3")
		(22 "In10.Cu" signal "GND4")
		(24 "In11.Cu" signal "IN4")
		(26 "In12.Cu" signal "GND5")
		(28 "In13.Cu" signal "IN5")
		(30 "In14.Cu" signal "GND6")
		(32 "In15.Cu" signal "IN6")
		(34 "In16.Cu" signal "GND7")
		(2 "B.Cu" signal "BOTTOM")
		(9 "F.Adhes" user "F.Adhesive")
		(11 "B.Adhes" user "B.Adhesive")
		(13 "F.Paste" user "Package Geometry/Pastemask Top")
		(15 "B.Paste" user "Package Geometry/Pastemask Bottom")
		(5 "F.SilkS" user "Ref Des/Silkscreen Top")
		(7 "B.SilkS" user "Ref Des/Silkscreen Bottom")
		(1 "F.Mask" user "Board Geometry/Soldermask Top")
		(3 "B.Mask" user "Board Geometry/Soldermask Bottom")
		(17 "Dwgs.User" user "User.Drawings")
		(19 "Cmts.User" user "User.Comments")
		(21 "Eco1.User" user "User.Eco1")
		(23 "Eco2.User" user "User.Eco2")
		(25 "Edge.Cuts" user "Board Geometry/Outline")
		(27 "Margin" user)
		(31 "F.CrtYd" user "Package Geometry/Place Bound Top")
		(29 "B.CrtYd" user "Package Geometry/Place Bound Bottom")
		(35 "F.Fab" user "Ref Des/Assembly Top")
		(33 "B.Fab" user "Ref Des/Assembly Bottom")
	)
	(footprint ""
		(layer "F.Cu")
		(at 183.326024 8.083804)
		(property "Reference" "DE11T_2"
			(at -3.6068 -2.962148 0)
			(unlocked yes)
			(layer "F.SilkS")
			(effects
				(font
					(size 0.7874 0.5842)
					(thickness 0.1524)
				)
				(justify left)
			)
		)
		(property "Value" ""
			(at 0 0 0)
			(layer "F.Fab")
			(effects
				(font
					(size 1.27 1.27)
				)
			)
		)
		(duplicate_pad_numbers_are_jumpers no)
		(fp_line
			(start -1.2192 -2.1082)
			(end 1.2192 -2.1082)
			(stroke
				(width 0.1524)
				(type default)
			)
			(layer "F.SilkS")
		)
		(fp_line
			(start -1.2192 2.1082)
			(end -1.2192 -2.1082)
			(stroke
				(width 0.1524)
				(type default)
			)
			(layer "F.SilkS")
		)
		(fp_line
			(start 1.2192 -2.1082)
			(end 1.2192 2.1082)
			(stroke
				(width 0.1524)
				(type default)
			)
			(layer "F.SilkS")
		)
		(fp_line
			(start 1.2192 2.1082)
			(end -1.2192 2.1082)
			(stroke
				(width 0.1524)
				(type default)
			)
			(layer "F.SilkS")
		)
		(pad "" np_thru_hole circle
			(at -2.8829 -1.27 270)
			(size 1.0414 1.0414)
			(drill 1.0414)
			(layers "*.Cu" "*.Mask")
			(clearance 0.381)
			(thermal_gap 0.381)
		)
		(pad "" np_thru_hole circle
			(at -2.8829 1.27 270)
			(size 1.0414 1.0414)
			(drill 1.0414)
			(layers "*.Cu" "*.Mask")
			(clearance 0.381)
			(thermal_gap 0.381)
		)
		(pad "" np_thru_hole circle
			(at 3.4671 -1.27 270)
			(size 1.0414 1.0414)
			(drill 1.0414)
			(layers "*.Cu" "*.Mask")
			(clearance 0.381)
			(thermal_gap 0.381)
		)
		(pad "" np_thru_hole circle
			(at 3.4671 1.27 270)
			(size 1.0414 1.0414)
			(drill 1.0414)
			(layers "*.Cu" "*.Mask")
			(clearance 0.381)
			(thermal_gap 0.381)
		)
		(pad "1" smd rect
			(at 0.8255 -0.249936 270)
			(size 0.3048 0.508)
			(layers "F.Cu" "F.Mask" "F.Paste")
			(net "85_10INCH_TOP_DP")
		)
		(pad "2" smd rect
			(at 0.8255 0.249936 270)
			(size 0.3048 0.508)
			(layers "F.Cu" "F.Mask" "F.Paste")
			(net "85_10INCH_TOP_DN")
		)
		(pad "3" smd circle
			(at 0 0)
			(size 0 0)
			(layers "F.Cu" "F.Mask" "F.Paste")
			(net "COUPON_GND2")
		)
		(zone
			(layer "F.Cu")
			(hatch none 0.5)
			(connect_pads
				(clearance 0)
			)
			(min_thickness 0.25)
			(keepout
				(tracks not_allowed)
				(vias allowed)
				(pads allowed)
				(copperpour not_allowed)
				(footprints allowed)
			)
			(placement
				(enabled no)
				(sheetname "")
			)
			(fill
				(thermal_gap 0.5)
				(thermal_bridge_width 0.5)
				(island_removal_mode 0)
			)
			(polygon
				(pts
					(xy 184.443624 7.535164) (xy 184.443624 7.630668) (xy 183.846724 7.630668) (xy 183.846724 8.037068)
					(xy 184.443624 8.037068) (xy 184.443624 8.13054) (xy 183.846724 8.13054) (xy 183.846724 8.53694)
					(xy 184.443624 8.53694) (xy 184.443624 8.632444) (xy 183.745124 8.632444) (xy 183.745124 7.535164)
				)
			)
		)
		(zone
			(layers "F.Cu" "B.Cu" "In1.Cu" "In2.Cu" "In3.Cu" "In4.Cu" "In5.Cu" "In6.Cu"
				"In7.Cu" "In8.Cu" "In9.Cu" "In10.Cu" "In11.Cu" "In12.Cu" "In13.Cu" "In14.Cu"
				"In15.Cu" "In16.Cu"
			)
			(hatch none 0.5)
			(connect_pads
				(clearance 0)
			)
			(min_thickness 0.25)
			(keepout
				(tracks not_allowed)
				(vias allowed)
				(pads allowed)
				(copperpour not_allowed)
				(footprints allowed)
			)
			(placement
				(enabled no)
				(sheetname "")
			)
			(fill
				(thermal_gap 0.5)
				(thermal_bridge_width 0.5)
				(island_removal_mode 0)
			)
			(polygon
				(pts
					(arc
						(start 181.370224 6.813804)
						(mid 179.516024 6.813804)
						(end 181.370224 6.813804)
					)
				)
			)
		)
		(zone
			(layers "F.Cu" "B.Cu" "In1.Cu" "In2.Cu" "In3.Cu" "In4.Cu" "In5.Cu" "In6.Cu"
				"In7.Cu" "In8.Cu" "In9.Cu" "In10.Cu" "In11.Cu" "In12.Cu" "In13.Cu" "In14.Cu"
				"In15.Cu" "In16.Cu"
			)
			(hatch none 0.5)
			(connect_pads
				(clearance 0)
			)
			(min_thickness 0.25)
			(keepout
				(tracks not_allowed)
				(vias allowed)
				(pads allowed)
				(copperpour not_allowed)
				(footprints allowed)
			)
			(placement
				(enabled no)
				(sheetname "")
			)
			(fill
				(thermal_gap 0.5)
				(thermal_bridge_width 0.5)
				(island_removal_mode 0)
			)
			(polygon
				(pts
					(arc
						(start 181.370224 9.353804)
						(mid 179.516024 9.353804)
						(end 181.370224 9.353804)
					)
				)
			)
		)
		(zone
			(layers "F.Cu" "B.Cu" "In1.Cu" "In2.Cu" "In3.Cu" "In4.Cu" "In5.Cu" "In6.Cu"
				"In7.Cu" "In8.Cu" "In9.Cu" "In10.Cu" "In11.Cu" "In12.Cu" "In13.Cu" "In14.Cu"
				"In15.Cu" "In16.Cu"
			)
			(hatch none 0.5)
			(connect_pads
				(clearance 0)
			)
			(min_thickness 0.25)
			(keepout
				(tracks not_allowed)
				(vias allowed)
				(pads allowed)
				(copperpour not_allowed)
				(footprints allowed)
			)
			(placement
				(enabled no)
				(sheetname "")
			)
			(fill
				(thermal_gap 0.5)
				(thermal_bridge_width 0.5)
				(island_removal_mode 0)
			)
			(polygon
				(pts
					(arc
						(start 187.720224 6.813804)
						(mid 185.866024 6.813804)
						(end 187.720224 6.813804)
					)
				)
			)
		)
		(zone
			(layers "F.Cu" "B.Cu" "In1.Cu" "In2.Cu" "In3.Cu" "In4.Cu" "In5.Cu" "In6.Cu"
				"In7.Cu" "In8.Cu" "In9.Cu" "In10.Cu" "In11.Cu" "In12.Cu" "In13.Cu" "In14.Cu"
				"In15.Cu" "In16.Cu"
			)
			(hatch none 0.5)
			(connect_pads
				(clearance 0)
			)
			(min_thickness 0.25)
			(keepout
				(tracks not_allowed)
				(vias allowed)
				(pads allowed)
				(copperpour not_allowed)
				(footprints allowed)
			)
			(placement
				(enabled no)
				(sheetname "")
			)
			(fill
				(thermal_gap 0.5)
				(thermal_bridge_width 0.5)
				(island_removal_mode 0)
			)
			(polygon
				(pts
					(arc
						(start 187.720224 9.353804)
						(mid 185.866024 9.353804)
						(end 187.720224 9.353804)
					)
				)
			)
		)
	)
	(footprint ""
		(layer "F.Cu")
		(at 470.347548 -538.74416 180)
		(property "Reference" "J44_OTH"
			(at -3.2385 -1.402334 0)
			(unlocked yes)
			(layer "B.SilkS")
			(effects
				(font
					(size 0.7874 0.5842)
					(thickness 0.1524)
				)
				(justify mirror)
			)
		)
		(property "Value" ""
			(at 0 0 180)
			(layer "F.Fab")
			(effects
				(font
					(size 1.27 1.27)
				)
			)
		)
		(duplicate_pad_numbers_are_jumpers no)
		(pad "1" thru_hole circle
			(at 0 0 180)
			(size 0.4572 0.4572)
			(drill 0.2032)
			(layers "*.Cu" "*.Mask")
			(remove_unused_layers no)
			(net "Net_9092")
			(clearance 0.127)
			(thermal_gap 0.127)
			(padstack
				(mode front_inner_back)
				(layer "Inner"
					(shape circle)
					(size 0.4572 0.4572)
					(clearance 0.127)
				)
				(layer "B.Cu"
					(shape circle)
					(size 0.508 0.508)
					(clearance 0.1016)
				)
			)
		)
	)
	(footprint ""
		(layer "F.Cu")
		(at 284.467808 -52.035456 180)
		(property "Reference" "R871"
			(at 0 0 180)
			(layer "F.SilkS")
			(hide yes)
			(effects
				(font
					(size 1.27 1.27)
				)
			)
		)
		(property "Value" ""
			(at 0 0 180)
			(layer "F.Fab")
			(effects
				(font
					(size 1.27 1.27)
				)
			)
		)
		(duplicate_pad_numbers_are_jumpers no)
		(fp_line
			(start 0.7874 0.4064)
			(end -0.7874 0.4064)
			(stroke
				(width 0.1524)
				(type default)
			)
			(layer "F.SilkS")
		)
		(fp_line
			(start 0.7874 -0.4064)
			(end 0.7874 0.4064)
			(stroke
				(width 0.1524)
				(type default)
			)
			(layer "F.SilkS")
		)
		(fp_line
			(start -0.7874 0.4064)
			(end -0.7874 -0.4064)
			(stroke
				(width 0.1524)
				(type default)
			)
			(layer "F.SilkS")
		)
		(fp_line
			(start -0.7874 -0.4064)
			(end 0.7874 -0.4064)
			(stroke
				(width 0.1524)
				(type default)
			)
			(layer "F.SilkS")
		)
		(fp_line
			(start 0.67945 0.3048)
			(end 0.120396 0.3048)
			(stroke
				(width 0.1)
				(type default)
			)
			(layer "F.Fab")
		)
		(fp_line
			(start 0.67945 -0.3048)
			(end 0.67945 0.3048)
			(stroke
				(width 0.1)
				(type default)
			)
			(layer "F.Fab")
		)
		(fp_line
			(start 0.12065 -0.2794)
			(end 0.12065 -0.3048)
			(stroke
				(width 0.1)
				(type default)
			)
			(layer "F.Fab")
		)
		(fp_line
			(start 0.12065 -0.3048)
			(end 0.67945 -0.3048)
			(stroke
				(width 0.1)
				(type default)
			)
			(layer "F.Fab")
		)
		(fp_line
			(start 0.120396 0.3048)
			(end 0.120396 0.2794)
			(stroke
				(width 0.1)
				(type default)
			)
			(layer "F.Fab")
		)
		(fp_line
			(start 0.120396 0.2794)
			(end -0.12065 0.2794)
			(stroke
				(width 0.1)
				(type default)
			)
			(layer "F.Fab")
		)
		(fp_line
			(start -0.12065 0.3048)
			(end -0.67945 0.3048)
			(stroke
				(width 0.1)
				(type default)
			)
			(layer "F.Fab")
		)
		(fp_line
			(start -0.12065 0.2794)
			(end -0.12065 0.3048)
			(stroke
				(width 0.1)
				(type default)
			)
			(layer "F.Fab")
		)
		(fp_line
			(start -0.12065 -0.2794)
			(end 0.12065 -0.2794)
			(stroke
				(width 0.1)
				(type default)
			)
			(layer "F.Fab")
		)
		(fp_line
			(start -0.12065 -0.305054)
			(end -0.12065 -0.2794)
			(stroke
				(width 0.1)
				(type default)
			)
			(layer "F.Fab")
		)
		(fp_line
			(start -0.67945 0.3048)
			(end -0.67945 -0.305054)
			(stroke
				(width 0.1)
				(type default)
			)
			(layer "F.Fab")
		)
		(fp_line
			(start -0.67945 -0.305054)
			(end -0.12065 -0.305054)
			(stroke
				(width 0.1)
				(type default)
			)
			(layer "F.Fab")
		)
		(pad "1" smd circle
			(at -0.40005 0 180)
			(size 0 0)
			(layers "F.Cu" "F.Mask" "F.Paste")
			(net "P3V3_AUX")
		)
		(pad "2" smd circle
			(at 0.40005 0 180)
			(size 0 0)
			(layers "F.Cu" "F.Mask" "F.Paste")
			(net "PWRGD_P12V_SSD9")
		)
	)
	(footprint ""
		(layer "F.Cu")
		(at 339.523324 -279.486868 -90)
		(property "Reference" "PR151"
			(at 0 0 270)
			(layer "F.SilkS")
			(hide yes)
			(effects
				(font
					(size 1.27 1.27)
				)
			)
		)
		(property "Value" ""
			(at 0 0 270)
			(layer "F.Fab")
			(effects
				(font
					(size 1.27 1.27)
				)
			)
		)
		(duplicate_pad_numbers_are_jumpers no)
		(fp_line
			(start -0.7874 0.4064)
			(end -0.7874 -0.4064)
			(stroke
				(width 0.1524)
				(type default)
			)
			(layer "F.SilkS")
		)
		(fp_line
			(start 0.7874 0.4064)
			(end -0.7874 0.4064)
			(stroke
				(width 0.1524)
				(type default)
			)
			(layer "F.SilkS")
		)
		(fp_line
			(start -0.7874 -0.4064)
			(end 0.7874 -0.4064)
			(stroke
				(width 0.1524)
				(type default)
			)
			(layer "F.SilkS")
		)
		(fp_line
			(start 0.7874 -0.4064)
			(end 0.7874 0.4064)
			(stroke
				(width 0.1524)
				(type default)
			)
			(layer "F.SilkS")
		)
		(fp_line
			(start -0.67945 0.3048)
			(end -0.67945 -0.305054)
			(stroke
				(width 0.1)
				(type default)
			)
			(layer "F.Fab")
		)
		(fp_line
			(start -0.12065 0.3048)
			(end -0.67945 0.3048)
			(stroke
				(width 0.1)
				(type default)
			)
			(layer "F.Fab")
		)
		(fp_line
			(start 0.120396 0.3048)
			(end 0.120396 0.2794)
			(stroke
				(width 0.1)
				(type default)
			)
			(layer "F.Fab")
		)
		(fp_line
			(start 0.67945 0.3048)
			(end 0.120396 0.3048)
			(stroke
				(width 0.1)
				(type default)
			)
			(layer "F.Fab")
		)
		(fp_line
			(start -0.12065 0.2794)
			(end -0.12065 0.3048)
			(stroke
				(width 0.1)
				(type default)
			)
			(layer "F.Fab")
		)
		(fp_line
			(start 0.120396 0.2794)
			(end -0.12065 0.2794)
			(stroke
				(width 0.1)
				(type default)
			)
			(layer "F.Fab")
		)
		(fp_line
			(start -0.12065 -0.2794)
			(end 0.12065 -0.2794)
			(stroke
				(width 0.1)
				(type default)
			)
			(layer "F.Fab")
		)
		(fp_line
			(start 0.12065 -0.2794)
			(end 0.12065 -0.3048)
			(stroke
				(width 0.1)
				(type default)
			)
			(layer "F.Fab")
		)
		(fp_line
			(start 0.12065 -0.3048)
			(end 0.67945 -0.3048)
			(stroke
				(width 0.1)
				(type default)
			)
			(layer "F.Fab")
		)
		(fp_line
			(start 0.67945 -0.3048)
			(end 0.67945 0.3048)
			(stroke
				(width 0.1)
				(type default)
			)
			(layer "F.Fab")
		)
		(fp_line
			(start -0.67945 -0.305054)
			(end -0.12065 -0.305054)
			(stroke
				(width 0.1)
				(type default)
			)
			(layer "F.Fab")
		)
		(fp_line
			(start -0.12065 -0.305054)
			(end -0.12065 -0.2794)
			(stroke
				(width 0.1)
				(type default)
			)
			(layer "F.Fab")
		)
		(pad "1" smd circle
			(at -0.40005 0 270)
			(size 0 0)
			(layers "F.Cu" "F.Mask" "F.Paste")
			(net "P0V8_PEX2_LSET1")
		)
		(pad "2" smd circle
			(at 0.40005 0 270)
			(size 0 0)
			(layers "F.Cu" "F.Mask" "F.Paste")
			(net "GND")
		)
	)
	(footprint ""
		(layer "F.Cu")
		(at 362.953808 -162.003994 -90)
		(property "Reference" "R960"
			(at 0 0 270)
			(layer "F.SilkS")
			(hide yes)
			(effects
				(font
					(size 1.27 1.27)
				)
			)
		)
		(property "Value" ""
			(at 0 0 270)
			(layer "F.Fab")
			(effects
				(font
					(size 1.27 1.27)
				)
			)
		)
		(duplicate_pad_numbers_are_jumpers no)
		(fp_line
			(start -0.7874 0.4064)
			(end -0.7874 -0.4064)
			(stroke
				(width 0.1524)
				(type default)
			)
			(layer "F.SilkS")
		)
		(fp_line
			(start 0.7874 0.4064)
			(end -0.7874 0.4064)
			(stroke
				(width 0.1524)
				(type default)
			)
			(layer "F.SilkS")
		)
		(fp_line
			(start -0.7874 -0.4064)
			(end 0.7874 -0.4064)
			(stroke
				(width 0.1524)
				(type default)
			)
			(layer "F.SilkS")
		)
		(fp_line
			(start 0.7874 -0.4064)
			(end 0.7874 0.4064)
			(stroke
				(width 0.1524)
				(type default)
			)
			(layer "F.SilkS")
		)
		(fp_line
			(start -0.67945 0.3048)
			(end -0.67945 -0.305054)
			(stroke
				(width 0.1)
				(type default)
			)
			(layer "F.Fab")
		)
		(fp_line
			(start -0.12065 0.3048)
			(end -0.67945 0.3048)
			(stroke
				(width 0.1)
				(type default)
			)
			(layer "F.Fab")
		)
		(fp_line
			(start 0.120396 0.3048)
			(end 0.120396 0.2794)
			(stroke
				(width 0.1)
				(type default)
			)
			(layer "F.Fab")
		)
		(fp_line
			(start 0.67945 0.3048)
			(end 0.120396 0.3048)
			(stroke
				(width 0.1)
				(type default)
			)
			(layer "F.Fab")
		)
		(fp_line
			(start -0.12065 0.2794)
			(end -0.12065 0.3048)
			(stroke
				(width 0.1)
				(type default)
			)
			(layer "F.Fab")
		)
		(fp_line
			(start 0.120396 0.2794)
			(end -0.12065 0.2794)
			(stroke
				(width 0.1)
				(type default)
			)
			(layer "F.Fab")
		)
		(fp_line
			(start -0.12065 -0.2794)
			(end 0.12065 -0.2794)
			(stroke
				(width 0.1)
				(type default)
			)
			(layer "F.Fab")
		)
		(fp_line
			(start 0.12065 -0.2794)
			(end 0.12065 -0.3048)
			(stroke
				(width 0.1)
				(type default)
			)
			(layer "F.Fab")
		)
		(fp_line
			(start 0.12065 -0.3048)
			(end 0.67945 -0.3048)
			(stroke
				(width 0.1)
				(type default)
			)
			(layer "F.Fab")
		)
		(fp_line
			(start 0.67945 -0.3048)
			(end 0.67945 0.3048)
			(stroke
				(width 0.1)
				(type default)
			)
			(layer "F.Fab")
		)
		(fp_line
			(start -0.67945 -0.305054)
			(end -0.12065 -0.305054)
			(stroke
				(width 0.1)
				(type default)
			)
			(layer "F.Fab")
		)
		(fp_line
			(start -0.12065 -0.305054)
			(end -0.12065 -0.2794)
			(stroke
				(width 0.1)
				(type default)
			)
			(layer "F.Fab")
		)
		(pad "1" smd circle
			(at -0.40005 0 270)
			(size 0 0)
			(layers "F.Cu" "F.Mask" "F.Paste")
			(net "GND")
		)
		(pad "2" smd circle
			(at 0.40005 0 270)
			(size 0 0)
			(layers "F.Cu" "F.Mask" "F.Paste")
			(net "P12V_NIC6_CO_EN")
		)
	)
	(footprint ""
		(layer "F.Cu")
		(at 451.298056 -266.996672 180)
		(property "Reference" "L130"
			(at 0 0 180)
			(layer "F.SilkS")
			(hide yes)
			(effects
				(font
					(size 1.27 1.27)
				)
			)
		)
		(property "Value" ""
			(at 0 0 180)
			(layer "F.Fab")
			(effects
				(font
					(size 1.27 1.27)
				)
			)
		)
		(duplicate_pad_numbers_are_jumpers no)
		(fp_line
			(start 2.248154 4.9911)
			(end 2.248154 1.680464)
			(stroke
				(width 0.1524)
				(type default)
			)
			(layer "F.SilkS")
		)
		(fp_line
			(start 2.248154 -1.701292)
			(end 2.248154 -4.9911)
			(stroke
				(width 0.1524)
				(type default)
			)
			(layer "F.SilkS")
		)
		(fp_line
			(start 2.248154 -4.9911)
			(end -2.248154 -4.9911)
			(stroke
				(width 0.1524)
				(type default)
			)
			(layer "F.SilkS")
		)
		(fp_line
			(start -2.248154 4.9911)
			(end 2.248154 4.9911)
			(stroke
				(width 0.1524)
				(type default)
			)
			(layer "F.SilkS")
		)
		(fp_line
			(start -2.248154 1.790192)
			(end -2.248154 4.9911)
			(stroke
				(width 0.1524)
				(type default)
			)
			(layer "F.SilkS")
		)
		(fp_line
			(start -2.248154 -4.9911)
			(end -2.248154 -1.701292)
			(stroke
				(width 0.1524)
				(type default)
			)
			(layer "F.SilkS")
		)
		(fp_line
			(start 1.700022 0.899922)
			(end 1.700022 -0.899922)
			(stroke
				(width 0.1)
				(type default)
			)
			(layer "F.Fab")
		)
		(fp_line
			(start 1.700022 -0.899922)
			(end -1.700022 -0.899922)
			(stroke
				(width 0.1)
				(type default)
			)
			(layer "F.Fab")
		)
		(fp_line
			(start -1.700022 0.899922)
			(end 1.700022 0.899922)
			(stroke
				(width 0.1)
				(type default)
			)
			(layer "F.Fab")
		)
		(fp_line
			(start -1.700022 -0.899922)
			(end -1.700022 0.899922)
			(stroke
				(width 0.1)
				(type default)
			)
			(layer "F.Fab")
		)
		(pad "1" smd rect
			(at -1.575054 0 180)
			(size 1.1684 9.8044)
			(layers "F.Cu" "F.Mask" "F.Paste")
			(net "P1V25_PEX3")
		)
		(pad "2" smd rect
			(at 1.575054 0 180)
			(size 1.1684 9.8044)
			(layers "F.Cu" "F.Mask" "F.Paste")
			(net "P1V25_SERDES_VDDPLL_PEX3")
		)
	)
)
